(kicad_pcb
	(version 20221018)
	(generator pcbnew)
	(general
    (thickness 1.562)
  )
	(paper "A4")
	(title_block
    (title "Thunderbolt PCIe Adaper")
    (date "2024-07-09")
    (rev "1.0.3")
    (comment 1 "www.antmicro.com")
    (comment 2 "Antmicro Ltd.")
		(comment 9 "footprints 228-235 of 271")
	)
	(layers
    (0 "F.Cu" signal)
    (1 "In1.Cu" signal)
    (2 "In2.Cu" signal)
    (3 "In3.Cu" signal)
    (4 "In4.Cu" signal)
    (31 "B.Cu" signal)
    (32 "B.Adhes" user "B.Adhesive")
    (33 "F.Adhes" user "F.Adhesive")
    (34 "B.Paste" user)
    (35 "F.Paste" user)
    (36 "B.SilkS" user "B.Silkscreen")
    (37 "F.SilkS" user "F.Silkscreen")
    (38 "B.Mask" user)
    (39 "F.Mask" user)
    (40 "Dwgs.User" user "User.Drawings")
    (41 "Cmts.User" user "User.Comments")
    (42 "Eco1.User" user "User.Eco1")
    (43 "Eco2.User" user "User.Eco2")
    (44 "Edge.Cuts" user)
    (45 "Margin" user)
    (46 "B.CrtYd" user "B.Courtyard")
    (47 "F.CrtYd" user "F.Courtyard")
    (48 "B.Fab" user)
    (49 "F.Fab" user)
  )
	(footprint "antmicro-footprints:R_0603_1608Metric" (layer "B.Cu")
    (at 112.13 91.83 -90)
    (descr "Resistor SMD 0603")
    (tags "resistor SMD 0603")
    (property "Author" "Antmicro")
    (property "License" "Apache-2.0")
    (property "MPN" "PMR03EZPJ000")
    (property "Manufacturer" "ROHM Semiconductor")
    (property "Max. Curr." "22.4A")
    (property "Sheetfile" "power.kicad_sch")
    (property "Sheetname" "Power")
    (property "Tolerance" "template_tolerance")
    (property "Val" "0R")
    (property "ki_description" "SMD Chip Resistor")
    (property "ki_keywords" "0603, SMT, RESISTOR, PASSIVE")
    (attr smd)
    (fp_text reference "R98" (at -1.025 0.751 90) (layer "B.SilkS")
        (effects (font (size 0.7 0.7) (thickness 0.15)) (justify left bottom mirror))
    )
    (fp_text value "R_0R_22.4A_0603" (at 0 -1.6 90) (layer "B.Fab")
        (effects (font (size 0.7 0.7) (thickness 0.15)) (justify left bottom mirror))
    )
    (fp_text user "Author: Antmicro" (at -1.25 -4.9 90) (layer "B.Fab") hide
        (effects (font (size 0.7 0.7) (thickness 0.15)) (justify left bottom mirror))
    )
    (fp_text user "${REFERENCE}" (at -1.25 -3.898 90) (layer "B.Fab") hide
        (effects (font (size 0.7 0.7) (thickness 0.15)) (justify left bottom mirror))
    )
    (fp_text user "License: Apache-2.0" (at -1.25 -5.9 90) (layer "B.Fab") hide
        (effects (font (size 0.7 0.7) (thickness 0.15)) (justify left bottom mirror))
    )
    (fp_line (start -0.15 -0.4) (end 0.15 -0.4)
      (stroke (width 0.15) (type solid)) (layer "B.SilkS"))
    (fp_line (start -0.15 0.4) (end 0.15 0.4)
      (stroke (width 0.15) (type solid)) (layer "B.SilkS"))
    (fp_rect (start -1.25 0.65) (end 1.25 -0.65)
      (stroke (width 0.05) (type solid)) (fill none) (layer "B.CrtYd"))
    (fp_rect (start -0.8 0.4) (end 0.8 -0.4)
      (stroke (width 0.15) (type solid)) (fill none) (layer "B.Fab"))
    (pad "1" smd roundrect (at -0.7 0 270) (size 0.8 1) (layers "B.Cu" "B.Paste" "B.Mask") (roundrect_rratio 0.2)
      (net 143 "Net-(Q3-S)") (pintype "passive"))
    (pad "2" smd roundrect (at 0.7 0 270) (size 0.8 1) (layers "B.Cu" "B.Paste" "B.Mask") (roundrect_rratio 0.2)
      (net 8 "12V0_PCIE") (pintype "passive"))
  )
	(footprint "antmicro-footprints:C_0402_1005Metric" (layer "B.Cu")
    (at 135.5 92.65 -90)
    (descr "Capacitor SMD 0402")
    (tags "capacitor SMD 0402")
    (property "Author" "Antmicro")
    (property "Dielectric" "")
    (property "License" "Apache-2.0")
    (property "MPN" "CC0402KRX5R6BB224")
    (property "Manufacturer" "YAGEO")
    (property "Sheetfile" "tb.kicad_sch")
    (property "Sheetname" "TB Controller")
    (property "Val" "220n")
    (property "Voltage" "")
    (property "ki_description" "SMD Multilayer Ceramic Capacitor, 0.22 µF, 10 V, 0402 [1005 Metric], ± 10%, X5R, CC Series")
    (property "ki_keywords" "0402, SMT, CAPACITOR, PASSIVE, MLCC, CERAMIC")
    (attr smd)
    (fp_text reference "C111" (at -3.877 -0.47 90) (layer "B.SilkS")
        (effects (font (size 0.7 0.7) (thickness 0.15)) (justify left bottom mirror))
    )
    (fp_text value "C_220n_0402" (at -1.022927 -2.155213 90) (layer "B.Fab")
        (effects (font (size 0.7 0.7) (thickness 0.15)) (justify left bottom mirror))
    )
    (fp_text user "License: Apache-2.0" (at -0.939 -5.799 90) (layer "B.Fab") hide
        (effects (font (size 0.7 0.7) (thickness 0.15)) (justify left bottom mirror))
    )
    (fp_text user "Author: Antmicro" (at -0.939 -3.399 90) (layer "B.Fab") hide
        (effects (font (size 0.7 0.7) (thickness 0.15)) (justify left bottom mirror))
    )
    (fp_text user "${REFERENCE}" (at -0.939 -4.599 90) (layer "B.Fab") hide
        (effects (font (size 0.7 0.7) (thickness 0.15)) (justify left bottom mirror))
    )
    (fp_rect (start -0.925 0.47) (end 0.925 -0.47)
      (stroke (width 0.05) (type default)) (fill none) (layer "B.CrtYd"))
    (fp_line (start -0.494 -0.248) (end -0.494 0.25)
      (stroke (width 0.15) (type solid)) (layer "B.Fab"))
    (fp_line (start -0.494 0.25) (end 0.504 0.25)
      (stroke (width 0.15) (type solid)) (layer "B.Fab"))
    (fp_line (start 0.504 -0.248) (end -0.494 -0.248)
      (stroke (width 0.15) (type solid)) (layer "B.Fab"))
    (fp_line (start 0.504 0.25) (end 0.504 -0.248)
      (stroke (width 0.15) (type solid)) (layer "B.Fab"))
    (pad "1" smd roundrect (at -0.48 0 270) (size 0.59 0.64) (layers "B.Cu" "B.Paste" "B.Mask") (roundrect_rratio 0.25)
      (net 82 "/TB Controller/TX2_P") (pintype "passive"))
    (pad "2" smd roundrect (at 0.48 0 270) (size 0.59 0.64) (layers "B.Cu" "B.Paste" "B.Mask") (roundrect_rratio 0.25)
      (net 30 "PCIE_TX2_P") (pintype "passive"))
  )
	(footprint "antmicro-footprints:C_0402_1005Metric" (layer "B.Cu")
    (at 130.9 79.85)
    (descr "Capacitor SMD 0402")
    (tags "capacitor SMD 0402")
    (property "Author" "Antmicro")
    (property "Dielectric" "")
    (property "License" "Apache-2.0")
    (property "MPN" "C1005X6S1A105K050BC")
    (property "Manufacturer" "TDK")
    (property "Sheetfile" "tb-power.kicad_sch")
    (property "Sheetname" "Thunderbolt Controller - Power")
    (property "Val" "1u")
    (property "Voltage" "")
    (property "ki_description" "SMD Multilayer Ceramic Capacitor, 1 µF, 10 V, 0402 [1005 Metric], ± 10%, X6S, C")
    (property "ki_keywords" "0402, SMT, CAPACITOR, PASSIVE, CERAMIC, MLCC")
    (attr smd)
    (fp_text reference "C55" (at 17.309 7.567 180) (layer "B.SilkS")
        (effects (font (size 0.7 0.7) (thickness 0.15)) (justify left bottom mirror))
    )
    (fp_text value "C_1u_0402" (at -1.022927 -2.155213 180) (layer "B.Fab")
        (effects (font (size 0.7 0.7) (thickness 0.15)) (justify left bottom mirror))
    )
    (fp_text user "${REFERENCE}" (at -0.939 -4.599 180) (layer "B.Fab") hide
        (effects (font (size 0.7 0.7) (thickness 0.15)) (justify left bottom mirror))
    )
    (fp_text user "Author: Antmicro" (at -0.939 -3.399 180) (layer "B.Fab") hide
        (effects (font (size 0.7 0.7) (thickness 0.15)) (justify left bottom mirror))
    )
    (fp_text user "License: Apache-2.0" (at -0.939 -5.799 180) (layer "B.Fab") hide
        (effects (font (size 0.7 0.7) (thickness 0.15)) (justify left bottom mirror))
    )
    (fp_rect (start -0.925 0.47) (end 0.925 -0.47)
      (stroke (width 0.05) (type default)) (fill none) (layer "B.CrtYd"))
    (fp_line (start -0.494 -0.248) (end -0.494 0.25)
      (stroke (width 0.15) (type solid)) (layer "B.Fab"))
    (fp_line (start -0.494 0.25) (end 0.504 0.25)
      (stroke (width 0.15) (type solid)) (layer "B.Fab"))
    (fp_line (start 0.504 -0.248) (end -0.494 -0.248)
      (stroke (width 0.15) (type solid)) (layer "B.Fab"))
    (fp_line (start 0.504 0.25) (end 0.504 -0.248)
      (stroke (width 0.15) (type solid)) (layer "B.Fab"))
    (pad "1" smd roundrect (at -0.48 0) (size 0.59 0.64) (layers "B.Cu" "B.Paste" "B.Mask") (roundrect_rratio 0.25)
      (net 1 "GND") (pintype "passive"))
    (pad "2" smd roundrect (at 0.48 0) (size 0.59 0.64) (layers "B.Cu" "B.Paste" "B.Mask") (roundrect_rratio 0.25)
      (net 106 "Net-(C53-Pad2)") (pintype "passive"))
  )
	(footprint "antmicro-footprints:R_0402_1005Metric" (layer "B.Cu")
    (at 133.125 70.72 90)
    (descr "Resistor SMD 0402")
    (tags "resistor SMD 0402")
    (property "Author" "Antmicro")
    (property "License" "Apache-2.0")
    (property "MPN" "CR0402-FX-1003GLF")
    (property "Manufacturer" "Bourns")
    (property "Sheetfile" "tb.kicad_sch")
    (property "Sheetname" "TB Controller")
    (property "Tolerance" "1%")
    (property "Val" "100k")
    (property "ki_description" "SMD Chip Resistor, 100 kohm, ± 1%, 62.5 mW, 0402 [1005 Metric], Thick Film, General Purpose")
    (property "ki_keywords" "0402, SMT, RESISTOR, PASSIVE")
    (attr smd)
    (fp_text reference "R77" (at -0.908 0.361 270) (layer "B.SilkS")
        (effects (font (size 0.7 0.7) (thickness 0.15)) (justify left bottom mirror))
    )
    (fp_text value "R_100k_0402" (at -1.011843 -1.772047 270) (layer "B.Fab")
        (effects (font (size 0.7 0.7) (thickness 0.15)) (justify left bottom mirror))
    )
    (fp_text user "License: Apache-2.0" (at -0.95 -5.169 270) (layer "B.Fab") hide
        (effects (font (size 0.7 0.7) (thickness 0.15)) (justify left bottom mirror))
    )
    (fp_text user "${REFERENCE}" (at -0.95 -3.168 270) (layer "B.Fab") hide
        (effects (font (size 0.7 0.7) (thickness 0.15)) (justify left bottom mirror))
    )
    (fp_text user "Author: Antmicro" (at -0.95 -4.169 270) (layer "B.Fab") hide
        (effects (font (size 0.7 0.7) (thickness 0.15)) (justify left bottom mirror))
    )
    (fp_rect (start -0.925 0.47) (end 0.925 -0.47)
      (stroke (width 0.05) (type default)) (fill none) (layer "B.CrtYd"))
    (fp_rect (start -0.5 0.25) (end 0.5 -0.25)
      (stroke (width 0.15) (type solid)) (fill none) (layer "B.Fab"))
    (pad "1" smd roundrect (at -0.48 0 90) (size 0.59 0.64) (layers "B.Cu" "B.Paste" "B.Mask") (roundrect_rratio 0.25)
      (net 192 "Net-(U4C-GPIO_3)") (pintype "passive"))
    (pad "2" smd roundrect (at 0.48 0 90) (size 0.59 0.64) (layers "B.Cu" "B.Paste" "B.Mask") (roundrect_rratio 0.25)
      (net 1 "GND") (pintype "passive"))
  )
	(footprint "antmicro-footprints:R_0402_1005Metric" (layer "B.Cu")
    (at 159.41 61.97 180)
    (descr "Resistor SMD 0402")
    (tags "resistor SMD 0402")
    (property "Author" "Antmicro")
    (property "License" "Apache-2.0")
    (property "MPN" "CR0402-FX-1002GLF")
    (property "Manufacturer" "Bourns")
    (property "Sheetfile" "power.kicad_sch")
    (property "Sheetname" "Power")
    (property "Tolerance" "1%")
    (property "Val" "10k")
    (property "ki_description" "SMD Chip Resistor, 10 kohm, ± 1%, 62.5 mW, 0402 [1005 Metric], Thick Film, General Purpose")
    (property "ki_keywords" "0402, SMT, RESISTOR, PASSIVE")
    (attr smd)
    (fp_text reference "R32" (at -1.166727 -2.16534) (layer "B.SilkS")
        (effects (font (size 0.7 0.7) (thickness 0.15)) (justify left bottom mirror))
    )
    (fp_text value "R_10k_0402" (at -1.011843 -1.772047) (layer "B.Fab")
        (effects (font (size 0.7 0.7) (thickness 0.15)) (justify left bottom mirror))
    )
    (fp_text user "License: Apache-2.0" (at -0.95 -5.169) (layer "B.Fab") hide
        (effects (font (size 0.7 0.7) (thickness 0.15)) (justify left bottom mirror))
    )
    (fp_text user "Author: Antmicro" (at -0.95 -4.169) (layer "B.Fab") hide
        (effects (font (size 0.7 0.7) (thickness 0.15)) (justify left bottom mirror))
    )
    (fp_text user "${REFERENCE}" (at -0.95 -3.168) (layer "B.Fab") hide
        (effects (font (size 0.7 0.7) (thickness 0.15)) (justify left bottom mirror))
    )
    (fp_rect (start -0.925 0.47) (end 0.925 -0.47)
      (stroke (width 0.05) (type default)) (fill none) (layer "B.CrtYd"))
    (fp_rect (start -0.5 0.25) (end 0.5 -0.25)
      (stroke (width 0.15) (type solid)) (fill none) (layer "B.Fab"))
    (pad "1" smd roundrect (at -0.48 0 180) (size 0.59 0.64) (layers "B.Cu" "B.Paste" "B.Mask") (roundrect_rratio 0.25)
      (net 165 "Net-(U3-MRESET(GPIO11))") (pintype "passive"))
    (pad "2" smd roundrect (at 0.48 0 180) (size 0.59 0.64) (layers "B.Cu" "B.Paste" "B.Mask") (roundrect_rratio 0.25)
      (net 1 "GND") (pintype "passive"))
  )
	(footprint "antmicro-footprints:C_0402_1005Metric" (layer "B.Cu")
    (at 143.15 76.432 90)
    (descr "Capacitor SMD 0402")
    (tags "capacitor SMD 0402")
    (property "Author" "Antmicro")
    (property "Dielectric" "")
    (property "License" "Apache-2.0")
    (property "MPN" "CC0402MRX5R5BB106")
    (property "Manufacturer" "YAGEO")
    (property "Sheetfile" "tb-power.kicad_sch")
    (property "Sheetname" "Thunderbolt Controller - Power")
    (property "Val" "10u")
    (property "Voltage" "")
    (property "ki_description" "SMD Multilayer Ceramic Capacitor, 10 µF, 6.3 V, 0402 [1005 Metric], ± 20%, X5R, CC Series")
    (property "ki_keywords" "0402, SMT, CAPACITOR, PASSIVE, MLCC, CERAMIC")
    (attr smd)
    (fp_text reference "C80" (at 5.439 1.503 270) (layer "B.SilkS")
        (effects (font (size 0.7 0.7) (thickness 0.15)) (justify left bottom mirror))
    )
    (fp_text value "C_10u_0402" (at -1.022927 -2.155213 270) (layer "B.Fab")
        (effects (font (size 0.7 0.7) (thickness 0.15)) (justify left bottom mirror))
    )
    (fp_text user "License: Apache-2.0" (at -0.939 -5.799 270) (layer "B.Fab") hide
        (effects (font (size 0.7 0.7) (thickness 0.15)) (justify left bottom mirror))
    )
    (fp_text user "Author: Antmicro" (at -0.939 -3.399 270) (layer "B.Fab") hide
        (effects (font (size 0.7 0.7) (thickness 0.15)) (justify left bottom mirror))
    )
    (fp_text user "${REFERENCE}" (at -0.939 -4.599 270) (layer "B.Fab") hide
        (effects (font (size 0.7 0.7) (thickness 0.15)) (justify left bottom mirror))
    )
    (fp_rect (start -0.925 0.47) (end 0.925 -0.47)
      (stroke (width 0.05) (type default)) (fill none) (layer "B.CrtYd"))
    (fp_line (start -0.494 -0.248) (end -0.494 0.25)
      (stroke (width 0.15) (type solid)) (layer "B.Fab"))
    (fp_line (start -0.494 0.25) (end 0.504 0.25)
      (stroke (width 0.15) (type solid)) (layer "B.Fab"))
    (fp_line (start 0.504 -0.248) (end -0.494 -0.248)
      (stroke (width 0.15) (type solid)) (layer "B.Fab"))
    (fp_line (start 0.504 0.25) (end 0.504 -0.248)
      (stroke (width 0.15) (type solid)) (layer "B.Fab"))
    (pad "1" smd roundrect (at -0.48 0 90) (size 0.59 0.64) (layers "B.Cu" "B.Paste" "B.Mask") (roundrect_rratio 0.25)
      (net 1 "GND") (pintype "passive"))
    (pad "2" smd roundrect (at 0.48 0 90) (size 0.59 0.64) (layers "B.Cu" "B.Paste" "B.Mask") (roundrect_rratio 0.25)
      (net 2 "3V3_SYS") (pintype "passive"))
  )
	(footprint "antmicro-footprints:R_0402_1005Metric" (layer "B.Cu")
    (at 102.390003 88.425 -90)
    (descr "Resistor SMD 0402")
    (tags "resistor SMD 0402")
    (property "Author" "Antmicro")
    (property "License" "Apache-2.0")
    (property "MPN" "CR0402-FX-1003GLF")
    (property "Manufacturer" "Bourns")
    (property "Sheetfile" "power.kicad_sch")
    (property "Sheetname" "Power")
    (property "Tolerance" "1%")
    (property "Val" "100k")
    (property "ki_description" "SMD Chip Resistor, 100 kohm, ± 1%, 62.5 mW, 0402 [1005 Metric], Thick Film, General Purpose")
    (property "ki_keywords" "0402, SMT, RESISTOR, PASSIVE")
    (attr smd)
    (fp_text reference "R92" (at -3.081 -0.45 90) (layer "B.SilkS")
        (effects (font (size 0.7 0.7) (thickness 0.15)) (justify left bottom mirror))
    )
    (fp_text value "R_100k_0402" (at -1.011843 -1.772047 90) (layer "B.Fab")
        (effects (font (size 0.7 0.7) (thickness 0.15)) (justify left bottom mirror))
    )
    (fp_text user "License: Apache-2.0" (at -0.95 -5.169 90) (layer "B.Fab") hide
        (effects (font (size 0.7 0.7) (thickness 0.15)) (justify left bottom mirror))
    )
    (fp_text user "Author: Antmicro" (at -0.95 -4.169 90) (layer "B.Fab") hide
        (effects (font (size 0.7 0.7) (thickness 0.15)) (justify left bottom mirror))
    )
    (fp_text user "${REFERENCE}" (at -0.95 -3.168 90) (layer "B.Fab") hide
        (effects (font (size 0.7 0.7) (thickness 0.15)) (justify left bottom mirror))
    )
    (fp_rect (start -0.925 0.47) (end 0.925 -0.47)
      (stroke (width 0.05) (type default)) (fill none) (layer "B.CrtYd"))
    (fp_rect (start -0.5 0.25) (end 0.5 -0.25)
      (stroke (width 0.15) (type solid)) (fill none) (layer "B.Fab"))
    (pad "1" smd roundrect (at -0.48 0 270) (size 0.59 0.64) (layers "B.Cu" "B.Paste" "B.Mask") (roundrect_rratio 0.25)
      (net 1 "GND") (pintype "passive"))
    (pad "2" smd roundrect (at 0.48 0 270) (size 0.59 0.64) (layers "B.Cu" "B.Paste" "B.Mask") (roundrect_rratio 0.25)
      (net 140 "Net-(Q2-B)") (pintype "passive"))
  )
	(footprint "antmicro-footprints:C_0402_1005Metric" (layer "B.Cu")
    (at 144.15 74.482 -90)
    (descr "Capacitor SMD 0402")
    (tags "capacitor SMD 0402")
    (property "Author" "Antmicro")
    (property "Dielectric" "")
    (property "License" "Apache-2.0")
    (property "MPN" "CC0402MRX5R5BB106")
    (property "Manufacturer" "YAGEO")
    (property "Sheetfile" "tb-power.kicad_sch")
    (property "Sheetname" "Thunderbolt Controller - Power")
    (property "Val" "10u")
    (property "Voltage" "")
    (property "ki_description" "SMD Multilayer Ceramic Capacitor, 10 µF, 6.3 V, 0402 [1005 Metric], ± 20%, X5R, CC Series")
    (property "ki_keywords" "0402, SMT, CAPACITOR, PASSIVE, MLCC, CERAMIC")
    (attr smd)
    (fp_text reference "C76" (at -5.521 -1.519 90) (layer "B.SilkS")
        (effects (font (size 0.7 0.7) (thickness 0.15)) (justify left bottom mirror))
    )
    (fp_text value "C_10u_0402" (at -1.022927 -2.155213 90) (layer "B.Fab")
        (effects (font (size 0.7 0.7) (thickness 0.15)) (justify left bottom mirror))
    )
    (fp_text user "Author: Antmicro" (at -0.939 -3.399 90) (layer "B.Fab") hide
        (effects (font (size 0.7 0.7) (thickness 0.15)) (justify left bottom mirror))
    )
    (fp_text user "License: Apache-2.0" (at -0.939 -5.799 90) (layer "B.Fab") hide
        (effects (font (size 0.7 0.7) (thickness 0.15)) (justify left bottom mirror))
    )
    (fp_text user "${REFERENCE}" (at -0.939 -4.599 90) (layer "B.Fab") hide
        (effects (font (size 0.7 0.7) (thickness 0.15)) (justify left bottom mirror))
    )
    (fp_rect (start -0.925 0.47) (end 0.925 -0.47)
      (stroke (width 0.05) (type default)) (fill none) (layer "B.CrtYd"))
    (fp_line (start -0.494 -0.248) (end -0.494 0.25)
      (stroke (width 0.15) (type solid)) (layer "B.Fab"))
    (fp_line (start -0.494 0.25) (end 0.504 0.25)
      (stroke (width 0.15) (type solid)) (layer "B.Fab"))
    (fp_line (start 0.504 -0.248) (end -0.494 -0.248)
      (stroke (width 0.15) (type solid)) (layer "B.Fab"))
    (fp_line (start 0.504 0.25) (end 0.504 -0.248)
      (stroke (width 0.15) (type solid)) (layer "B.Fab"))
    (pad "1" smd roundrect (at -0.48 0 270) (size 0.59 0.64) (layers "B.Cu" "B.Paste" "B.Mask") (roundrect_rratio 0.25)
      (net 1 "GND") (pintype "passive"))
    (pad "2" smd roundrect (at 0.48 0 270) (size 0.59 0.64) (layers "B.Cu" "B.Paste" "B.Mask") (roundrect_rratio 0.25)
      (net 2 "3V3_SYS") (pintype "passive"))
  )
)
